# T6G (Grand Teton) — schematic netlist excerpt (pin names and nets, part order shuffled) for the footprints in the layout excerpt that follows; sources: Cadence DE-HDL packaged netlist, KiCad conversion of 04192023_DAF0TMB3IC0_F0TG_MB_C_brd_V02_OCP.brd

R1593  Q_RES  33 5% CHIP  pkg 0402LF  page 29 : A = ESPI_CPU0_ALERT_P0_N ; B = CPU0_ESPI0_ALERT_N
R1361  Q_RES  4.7K 5% CHIP  pkg 0201LF  page 185 : A = P1V8_CPU1_RT_1D ; B = SMB_RT_CPU1_P0_ROM_MUX_2D_R_SDA
R1402  Q_RES  4.7K 5% CHIP  pkg 0201LF  page 185 : A = P1V8_CPU1_RT_1D ; B = SMB_RT_CPU1_P3_ROM_MUX_2D_R_SCL

(kicad_pcb
	(version 20260206)
	(generator "pcbnew")
	(generator_version "10.0")
	(general
		(thickness 1.6)
		(legacy_teardrops no)
	)
	(paper "A4")
	(title_block
		(title "04192023_DAF0TMB3IC0_F0TG_MB_C_brd_V02_OCP.brd")
		(comment 1 "Grand Teton / footprints 6546-6548 of 8354")
	)
	(layers
		(0 "F.Cu" signal "TOP")
		(4 "In1.Cu" signal "GND")
		(6 "In2.Cu" signal "IN1")
		(8 "In3.Cu" signal "GND1")
		(10 "In4.Cu" signal "IN2")
		(12 "In5.Cu" signal "GND2")
		(14 "In6.Cu" signal "IN3")
		(16 "In7.Cu" signal "GND3")
		(18 "In8.Cu" signal "VCC")
		(20 "In9.Cu" signal "VCC1")
		(22 "In10.Cu" signal "GND4")
		(24 "In11.Cu" signal "IN4")
		(26 "In12.Cu" signal "GND5")
		(28 "In13.Cu" signal "IN5")
		(30 "In14.Cu" signal "GND6")
		(32 "In15.Cu" signal "IN6")
		(34 "In16.Cu" signal "GND7")
		(2 "B.Cu" signal "BOTTOM")
		(9 "F.Adhes" user "F.Adhesive")
		(11 "B.Adhes" user "B.Adhesive")
		(13 "F.Paste" user "Package Geometry/Pastemask Top")
		(15 "B.Paste" user "Package Geometry/Pastemask Bottom")
		(5 "F.SilkS" user "Ref Des/Silkscreen Top")
		(7 "B.SilkS" user "Ref Des/Silkscreen Bottom")
		(1 "F.Mask" user "Board Geometry/Soldermask Top")
		(3 "B.Mask" user "Board Geometry/Soldermask Bottom")
		(17 "Dwgs.User" user "User.Drawings")
		(19 "Cmts.User" user "User.Comments")
		(21 "Eco1.User" user "User.Eco1")
		(23 "Eco2.User" user "User.Eco2")
		(25 "Edge.Cuts" user "Board Geometry/Outline")
		(27 "Margin" user)
		(31 "F.CrtYd" user "Package Geometry/Place Bound Top")
		(29 "B.CrtYd" user "Package Geometry/Place Bound Bottom")
		(35 "F.Fab" user "Ref Des/Assembly Top")
		(33 "B.Fab" user "Ref Des/Assembly Bottom")
	)
	(footprint ""
		(layer "B.Cu")
		(at 404.115778 -323.892672 180)
		(property "Reference" "R1593"
			(at 0 0 0)
			(layer "B.SilkS")
			(hide yes)
			(effects
				(font
					(size 1.27 1.27)
				)
				(justify mirror)
			)
		)
		(property "Value" ""
			(at 0 0 0)
			(layer "B.Fab")
			(effects
				(font
					(size 1.27 1.27)
				)
				(justify mirror)
			)
		)
		(duplicate_pad_numbers_are_jumpers no)
		(fp_line
			(start 0.7874 0.4064)
			(end 0.7874 -0.4064)
			(stroke
				(width 0.1524)
				(type default)
			)
			(layer "B.SilkS")
		)
		(fp_line
			(start 0.7874 -0.4064)
			(end -0.7874 -0.4064)
			(stroke
				(width 0.1524)
				(type default)
			)
			(layer "B.SilkS")
		)
		(fp_line
			(start -0.7874 0.4064)
			(end 0.7874 0.4064)
			(stroke
				(width 0.1524)
				(type default)
			)
			(layer "B.SilkS")
		)
		(fp_line
			(start -0.7874 -0.4064)
			(end -0.7874 0.4064)
			(stroke
				(width 0.1524)
				(type default)
			)
			(layer "B.SilkS")
		)
		(fp_line
			(start 0.67945 0.3048)
			(end 0.67945 -0.305054)
			(stroke
				(width 0.1)
				(type default)
			)
			(layer "B.Fab")
		)
		(fp_line
			(start 0.67945 -0.305054)
			(end 0.12065 -0.305054)
			(stroke
				(width 0.1)
				(type default)
			)
			(layer "B.Fab")
		)
		(fp_line
			(start 0.12065 0.3048)
			(end 0.67945 0.3048)
			(stroke
				(width 0.1)
				(type default)
			)
			(layer "B.Fab")
		)
		(fp_line
			(start 0.12065 0.2794)
			(end 0.12065 0.3048)
			(stroke
				(width 0.1)
				(type default)
			)
			(layer "B.Fab")
		)
		(fp_line
			(start 0.12065 -0.2794)
			(end -0.12065 -0.2794)
			(stroke
				(width 0.1)
				(type default)
			)
			(layer "B.Fab")
		)
		(fp_line
			(start 0.12065 -0.305054)
			(end 0.12065 -0.2794)
			(stroke
				(width 0.1)
				(type default)
			)
			(layer "B.Fab")
		)
		(fp_line
			(start -0.120396 0.3048)
			(end -0.120396 0.2794)
			(stroke
				(width 0.1)
				(type default)
			)
			(layer "B.Fab")
		)
		(fp_line
			(start -0.120396 0.2794)
			(end 0.12065 0.2794)
			(stroke
				(width 0.1)
				(type default)
			)
			(layer "B.Fab")
		)
		(fp_line
			(start -0.12065 -0.2794)
			(end -0.12065 -0.3048)
			(stroke
				(width 0.1)
				(type default)
			)
			(layer "B.Fab")
		)
		(fp_line
			(start -0.12065 -0.3048)
			(end -0.67945 -0.3048)
			(stroke
				(width 0.1)
				(type default)
			)
			(layer "B.Fab")
		)
		(fp_line
			(start -0.67945 0.3048)
			(end -0.120396 0.3048)
			(stroke
				(width 0.1)
				(type default)
			)
			(layer "B.Fab")
		)
		(fp_line
			(start -0.67945 -0.3048)
			(end -0.67945 0.3048)
			(stroke
				(width 0.1)
				(type default)
			)
			(layer "B.Fab")
		)
		(pad "1" smd rect
			(at 0.40005 0 180)
			(size 0.4572 0.508)
			(layers "B.Cu" "B.Mask" "B.Paste")
			(net "ESPI_CPU0_ALERT_P0_N")
		)
		(pad "2" smd rect
			(at -0.40005 0 180)
			(size 0.4572 0.508)
			(layers "B.Cu" "B.Mask" "B.Paste")
			(net "CPU0_ESPI0_ALERT_N")
		)
	)
	(footprint ""
		(layer "B.Cu")
		(at 239.903 -333.883)
		(property "Reference" "R1361"
			(at 0 0 0)
			(layer "B.SilkS")
			(hide yes)
			(effects
				(font
					(size 1.27 1.27)
				)
				(justify mirror)
			)
		)
		(property "Value" ""
			(at 0 0 0)
			(layer "B.Fab")
			(effects
				(font
					(size 1.27 1.27)
				)
				(justify mirror)
			)
		)
		(duplicate_pad_numbers_are_jumpers no)
		(fp_line
			(start -0.32512 -0.175006)
			(end -0.32512 0.175006)
			(stroke
				(width 0.1)
				(type default)
			)
			(layer "B.Fab")
		)
		(fp_line
			(start -0.32512 0.175006)
			(end 0.32512 0.175006)
			(stroke
				(width 0.1)
				(type default)
			)
			(layer "B.Fab")
		)
		(fp_line
			(start 0.32512 -0.175006)
			(end -0.32512 -0.175006)
			(stroke
				(width 0.1)
				(type default)
			)
			(layer "B.Fab")
		)
		(fp_line
			(start 0.32512 0.175006)
			(end 0.32512 -0.175006)
			(stroke
				(width 0.1)
				(type default)
			)
			(layer "B.Fab")
		)
		(pad "1" smd rect
			(at 0.2667 0 180)
			(size 0.3048 0.381)
			(layers "B.Cu" "B.Mask" "B.Paste")
			(net "P1V8_CPU1_RT_1D")
		)
		(pad "2" smd rect
			(at -0.2667 0)
			(size 0.3048 0.381)
			(layers "B.Cu" "B.Mask" "B.Paste")
			(net "SMB_RT_CPU1_P0_ROM_MUX_2D_R_SDA")
		)
	)
	(footprint ""
		(layer "B.Cu")
		(at 239.903 -339.598)
		(property "Reference" "R1402"
			(at 0 0 0)
			(layer "B.SilkS")
			(hide yes)
			(effects
				(font
					(size 1.27 1.27)
				)
				(justify mirror)
			)
		)
		(property "Value" ""
			(at 0 0 0)
			(layer "B.Fab")
			(effects
				(font
					(size 1.27 1.27)
				)
				(justify mirror)
			)
		)
		(duplicate_pad_numbers_are_jumpers no)
		(fp_line
			(start -0.32512 -0.175006)
			(end -0.32512 0.175006)
			(stroke
				(width 0.1)
				(type default)
			)
			(layer "B.Fab")
		)
		(fp_line
			(start -0.32512 0.175006)
			(end 0.32512 0.175006)
			(stroke
				(width 0.1)
				(type default)
			)
			(layer "B.Fab")
		)
		(fp_line
			(start 0.32512 -0.175006)
			(end -0.32512 -0.175006)
			(stroke
				(width 0.1)
				(type default)
			)
			(layer "B.Fab")
		)
		(fp_line
			(start 0.32512 0.175006)
			(end 0.32512 -0.175006)
			(stroke
				(width 0.1)
				(type default)
			)
			(layer "B.Fab")
		)
		(pad "1" smd rect
			(at 0.2667 0 180)
			(size 0.3048 0.381)
			(layers "B.Cu" "B.Mask" "B.Paste")
			(net "P1V8_CPU1_RT_1D")
		)
		(pad "2" smd rect
			(at -0.2667 0)
			(size 0.3048 0.381)
			(layers "B.Cu" "B.Mask" "B.Paste")
			(net "SMB_RT_CPU1_P3_ROM_MUX_2D_R_SCL")
		)
	)
)
